(kicad_pcb
	(version 20241229)
	(generator "pcbnew")
	(generator_version "9.0")
	(general
		(thickness 1.294)
		(legacy_teardrops no)
	)
	(paper "A3")
	(title_block
		(title "Kintex 410T devboard")
		(date "2024-04-03")
		(rev "1.1.2")
		(comment 9 "footprints 182-186 of 975")
	)
	(layers
		(0 "F.Cu" mixed)
		(4 "In1.Cu" power)
		(6 "In2.Cu" power)
		(8 "In3.Cu" mixed)
		(10 "In4.Cu" power)
		(12 "In5.Cu" mixed)
		(14 "In6.Cu" power)
		(16 "In7.Cu" mixed)
		(18 "In8.Cu" power)
		(2 "B.Cu" mixed)
		(9 "F.Adhes" user "F.Adhesive")
		(11 "B.Adhes" user "B.Adhesive")
		(13 "F.Paste" user)
		(15 "B.Paste" user)
		(5 "F.SilkS" user "F.Silkscreen")
		(7 "B.SilkS" user "B.Silkscreen")
		(1 "F.Mask" user)
		(3 "B.Mask" user)
		(17 "Dwgs.User" user "User.Drawings")
		(19 "Cmts.User" user "User.Comments")
		(21 "Eco1.User" user "User.Eco1")
		(23 "Eco2.User" user "User.Eco2")
		(25 "Edge.Cuts" user)
		(27 "Margin" user)
		(31 "F.CrtYd" user "F.Courtyard")
		(29 "B.CrtYd" user "B.Courtyard")
		(35 "F.Fab" user)
		(33 "B.Fab" user)
	)
	(footprint "antmicro-footprints:C_0402_1005Metric"
		(layer "F.Cu")
		(at 207.403752 92.6615 180)
		(descr "Capacitor SMD 0402")
		(tags "capacitor SMD 0402")
		(property "Reference" "C287"
			(at 1.753752 5.1115 180)
			(layer "F.SilkS")
			(effects
				(font
					(size 0.7 0.7)
					(thickness 0.15)
				)
				(justify left bottom)
			)
		)
		(property "Value" "C_100n_0402"
			(at 0 1.169 180)
			(layer "F.Fab")
			(effects
				(font
					(size 0.7 0.7)
					(thickness 0.15)
				)
				(justify left bottom)
			)
		)
		(property "Description" "SMD Multilayer Ceramic Capacitor, 0.1 µF, 50 V, 0402 [1005 Metric], ± 10%, X5R, GRM Series"
			(at 0 0 180)
			(layer "F.Fab")
			(hide yes)
			(effects
				(font
					(size 1.27 1.27)
					(thickness 0.15)
				)
			)
		)
		(property "Author" "Antmicro"
			(at 414.807504 185.323 0)
			(layer "F.Fab")
			(hide yes)
			(effects
				(font
					(size 1 1)
					(thickness 0.15)
				)
			)
		)
		(property "Dielectric" "X5R"
			(at 414.807504 185.323 0)
			(layer "F.Fab")
			(hide yes)
			(effects
				(font
					(size 1 1)
					(thickness 0.15)
				)
			)
		)
		(property "License" "Apache-2.0"
			(at 414.807504 185.323 0)
			(layer "F.Fab")
			(hide yes)
			(effects
				(font
					(size 1 1)
					(thickness 0.15)
				)
			)
		)
		(property "MPN" "GRM155R61H104KE14D"
			(at 414.807504 185.323 0)
			(layer "F.Fab")
			(hide yes)
			(effects
				(font
					(size 1 1)
					(thickness 0.15)
				)
			)
		)
		(property "Manufacturer" "Murata"
			(at 414.807504 185.323 0)
			(layer "F.Fab")
			(hide yes)
			(effects
				(font
					(size 1 1)
					(thickness 0.15)
				)
			)
		)
		(property "Val" "100n"
			(at 414.807504 185.323 0)
			(layer "F.Fab")
			(hide yes)
			(effects
				(font
					(size 1 1)
					(thickness 0.15)
				)
			)
		)
		(property "Voltage" "50V"
			(at 414.807504 185.323 0)
			(layer "F.Fab")
			(hide yes)
			(effects
				(font
					(size 1 1)
					(thickness 0.15)
				)
			)
		)
		(sheetname "HDMI + Ethernet")
		(sheetfile "hdmi-ethernet.kicad_sch")
		(attr smd)
		(fp_rect
			(start -0.925 -0.47)
			(end 0.925 0.47)
			(stroke
				(width 0.05)
				(type default)
			)
			(fill no)
			(layer "F.CrtYd")
		)
		(fp_line
			(start 0.504 0.248)
			(end -0.494 0.248)
			(stroke
				(width 0.15)
				(type solid)
			)
			(layer "F.Fab")
		)
		(fp_line
			(start 0.504 -0.25)
			(end 0.504 0.248)
			(stroke
				(width 0.15)
				(type solid)
			)
			(layer "F.Fab")
		)
		(fp_line
			(start -0.494 0.248)
			(end -0.494 -0.25)
			(stroke
				(width 0.15)
				(type solid)
			)
			(layer "F.Fab")
		)
		(fp_line
			(start -0.494 -0.25)
			(end 0.504 -0.25)
			(stroke
				(width 0.15)
				(type solid)
			)
			(layer "F.Fab")
		)
		(pad "1" smd roundrect
			(at -0.48 0 180)
			(size 0.59 0.64)
			(layers "F.Cu" "F.Mask" "F.Paste")
			(roundrect_rratio 0.25)
			(net 1 "GND")
			(pintype "passive")
		)
		(pad "2" smd roundrect
			(at 0.48 0 180)
			(size 0.59 0.64)
			(layers "F.Cu" "F.Mask" "F.Paste")
			(roundrect_rratio 0.25)
			(net 728 "/HDMI + Ethernet/GBE_AVDDL{slash}PLL")
			(pintype "passive")
		)
	)
	(footprint "antmicro-footprints:C_0402_1005Metric"
		(layer "F.Cu")
		(at 248.7 141.6 90)
		(descr "Capacitor SMD 0402")
		(tags "capacitor SMD 0402")
		(property "Reference" "C230"
			(at -1.55 -0.45 90)
			(layer "F.SilkS")
			(effects
				(font
					(size 0.7 0.7)
					(thickness 0.15)
				)
				(justify left bottom)
			)
		)
		(property "Value" "C_100n_0402"
			(at 0 1.169 90)
			(layer "F.Fab")
			(effects
				(font
					(size 0.7 0.7)
					(thickness 0.15)
				)
				(justify left bottom)
			)
		)
		(property "Description" "SMD Multilayer Ceramic Capacitor, 0.1 µF, 50 V, 0402 [1005 Metric], ± 10%, X5R, GRM Series"
			(at 0 0 90)
			(layer "F.Fab")
			(hide yes)
			(effects
				(font
					(size 1.27 1.27)
					(thickness 0.15)
				)
			)
		)
		(property "Author" "Antmicro"
			(at 390.3 -107.1 0)
			(layer "F.Fab")
			(hide yes)
			(effects
				(font
					(size 1 1)
					(thickness 0.15)
				)
			)
		)
		(property "Dielectric" "X5R"
			(at 390.3 -107.1 0)
			(layer "F.Fab")
			(hide yes)
			(effects
				(font
					(size 1 1)
					(thickness 0.15)
				)
			)
		)
		(property "License" "Apache-2.0"
			(at 390.3 -107.1 0)
			(layer "F.Fab")
			(hide yes)
			(effects
				(font
					(size 1 1)
					(thickness 0.15)
				)
			)
		)
		(property "MPN" "GRM155R61H104KE14D"
			(at 390.3 -107.1 0)
			(layer "F.Fab")
			(hide yes)
			(effects
				(font
					(size 1 1)
					(thickness 0.15)
				)
			)
		)
		(property "Manufacturer" "Murata"
			(at 390.3 -107.1 0)
			(layer "F.Fab")
			(hide yes)
			(effects
				(font
					(size 1 1)
					(thickness 0.15)
				)
			)
		)
		(property "Val" "100n"
			(at 390.3 -107.1 0)
			(layer "F.Fab")
			(hide yes)
			(effects
				(font
					(size 1 1)
					(thickness 0.15)
				)
			)
		)
		(property "Voltage" "50V"
			(at 390.3 -107.1 0)
			(layer "F.Fab")
			(hide yes)
			(effects
				(font
					(size 1 1)
					(thickness 0.15)
				)
			)
		)
		(sheetname "USB PHY")
		(sheetfile "usb-phy.kicad_sch")
		(attr smd)
		(fp_rect
			(start -0.925 -0.47)
			(end 0.925 0.47)
			(stroke
				(width 0.05)
				(type default)
			)
			(fill no)
			(layer "F.CrtYd")
		)
		(fp_line
			(start 0.504 -0.25)
			(end 0.504 0.248)
			(stroke
				(width 0.15)
				(type solid)
			)
			(layer "F.Fab")
		)
		(fp_line
			(start -0.494 -0.25)
			(end 0.504 -0.25)
			(stroke
				(width 0.15)
				(type solid)
			)
			(layer "F.Fab")
		)
		(fp_line
			(start 0.504 0.248)
			(end -0.494 0.248)
			(stroke
				(width 0.15)
				(type solid)
			)
			(layer "F.Fab")
		)
		(fp_line
			(start -0.494 0.248)
			(end -0.494 -0.25)
			(stroke
				(width 0.15)
				(type solid)
			)
			(layer "F.Fab")
		)
		(pad "1" smd roundrect
			(at -0.48 0 90)
			(size 0.59 0.64)
			(layers "F.Cu" "F.Mask" "F.Paste")
			(roundrect_rratio 0.25)
			(net 1 "GND")
			(pintype "passive")
		)
		(pad "2" smd roundrect
			(at 0.48 0 90)
			(size 0.59 0.64)
			(layers "F.Cu" "F.Mask" "F.Paste")
			(roundrect_rratio 0.25)
			(net 707 "/USB PHY/FTDI_3V3")
			(pintype "passive")
		)
	)
	(footprint "antmicro-footprints:R_0402_1005Metric"
		(layer "F.Cu")
		(at 236 135.4 180)
		(descr "Resistor SMD 0402")
		(tags "resistor SMD 0402")
		(property "Reference" "R196"
			(at 1.6 1.35 180)
			(layer "F.SilkS")
			(effects
				(font
					(size 0.7 0.7)
					(thickness 0.15)
				)
				(justify left bottom)
			)
		)
		(property "Value" "R_4k7_0402"
			(at 0 1.4 180)
			(layer "F.Fab")
			(effects
				(font
					(size 0.7 0.7)
					(thickness 0.15)
				)
				(justify left bottom)
			)
		)
		(property "Description" "SMD Chip Resistor, 4.7 kohm, ± 1%, 62.5 mW, 0402 [1005 Metric], Thick Film, General Purpose"
			(at 0 0 180)
			(layer "F.Fab")
			(hide yes)
			(effects
				(font
					(size 1.27 1.27)
					(thickness 0.15)
				)
			)
		)
		(property "Author" "Antmicro"
			(at 472 270.8 0)
			(layer "F.Fab")
			(hide yes)
			(effects
				(font
					(size 1 1)
					(thickness 0.15)
				)
			)
		)
		(property "License" "Apache-2.0"
			(at 472 270.8 0)
			(layer "F.Fab")
			(hide yes)
			(effects
				(font
					(size 1 1)
					(thickness 0.15)
				)
			)
		)
		(property "MPN" "CR0402-FX-4701GLF"
			(at 472 270.8 0)
			(layer "F.Fab")
			(hide yes)
			(effects
				(font
					(size 1 1)
					(thickness 0.15)
				)
			)
		)
		(property "Manufacturer" "Bourns"
			(at 472 270.8 0)
			(layer "F.Fab")
			(hide yes)
			(effects
				(font
					(size 1 1)
					(thickness 0.15)
				)
			)
		)
		(property "Tolerance" "1%"
			(at 472 270.8 0)
			(layer "F.Fab")
			(hide yes)
			(effects
				(font
					(size 1 1)
					(thickness 0.15)
				)
			)
		)
		(property "Val" "4k7"
			(at 472 270.8 0)
			(layer "F.Fab")
			(hide yes)
			(effects
				(font
					(size 1 1)
					(thickness 0.15)
				)
			)
		)
		(sheetname "USB PHY")
		(sheetfile "usb-phy.kicad_sch")
		(attr smd)
		(fp_rect
			(start -0.925 -0.47)
			(end 0.925 0.47)
			(stroke
				(width 0.05)
				(type default)
			)
			(fill no)
			(layer "F.CrtYd")
		)
		(fp_rect
			(start -0.5 -0.25)
			(end 0.5 0.25)
			(stroke
				(width 0.15)
				(type solid)
			)
			(fill no)
			(layer "F.Fab")
		)
		(pad "1" smd roundrect
			(at -0.48 0 180)
			(size 0.59 0.64)
			(layers "F.Cu" "F.Mask" "F.Paste")
			(roundrect_rratio 0.25)
			(net 1205 "Net-(D38-Pad1)")
			(pintype "passive")
		)
		(pad "2" smd roundrect
			(at 0.48 0 180)
			(size 0.59 0.64)
			(layers "F.Cu" "F.Mask" "F.Paste")
			(roundrect_rratio 0.25)
			(net 1336 "/I2C.SDA")
			(pintype "passive")
		)
	)
	(footprint "antmicro-footprints:LED_0603_1608Metric_R"
		(layer "F.Cu")
		(at 257.06 185.95 180)
		(descr "LED SMD 0603 Red")
		(tags "LED SMD 0603 Red")
		(property "Reference" "D9"
			(at -1.24 0.7 0)
			(layer "F.SilkS")
			(effects
				(font
					(size 0.7 0.7)
					(thickness 0.15)
				)
				(justify right bottom)
			)
		)
		(property "Value" "LED_R_0603_KP-1608EC"
			(at 0 1.6 0)
			(layer "F.Fab")
			(effects
				(font
					(size 0.7 0.7)
					(thickness 0.15)
				)
				(justify right bottom)
			)
		)
		(property "Description" "LED, Red, SMD, 0603, 30 mA, 2 V, 617 nm"
			(at 0 0 180)
			(layer "F.Fab")
			(hide yes)
			(effects
				(font
					(size 1.27 1.27)
					(thickness 0.15)
				)
			)
		)
		(property "Author" "Antmicro"
			(at 514.12 371.9 0)
			(layer "F.Fab")
			(hide yes)
			(effects
				(font
					(size 1 1)
					(thickness 0.15)
				)
			)
		)
		(property "Color" "Red"
			(at 514.12 371.9 0)
			(layer "F.Fab")
			(hide yes)
			(effects
				(font
					(size 1 1)
					(thickness 0.15)
				)
			)
		)
		(property "License" "Apache-2.0"
			(at 514.12 371.9 0)
			(layer "F.Fab")
			(hide yes)
			(effects
				(font
					(size 1 1)
					(thickness 0.15)
				)
			)
		)
		(property "MPN" "KP-1608EC"
			(at 514.12 371.9 0)
			(layer "F.Fab")
			(hide yes)
			(effects
				(font
					(size 1 1)
					(thickness 0.15)
				)
			)
		)
		(property "Manufacturer" "Kingbright"
			(at 514.12 371.9 0)
			(layer "F.Fab")
			(hide yes)
			(effects
				(font
					(size 1 1)
					(thickness 0.15)
				)
			)
		)
		(property "Public" "False"
			(at 514.12 371.9 0)
			(layer "F.Fab")
			(hide yes)
			(effects
				(font
					(size 1 1)
					(thickness 0.15)
				)
			)
		)
		(sheetname "Power supply")
		(sheetfile "power-supply.kicad_sch")
		(attr smd)
		(fp_line
			(start 0.22 0.35)
			(end -0.22 0.35)
			(stroke
				(width 0.15)
				(type solid)
			)
			(layer "F.SilkS")
		)
		(fp_line
			(start 0.22 -0.35)
			(end -0.22 -0.35)
			(stroke
				(width 0.15)
				(type solid)
			)
			(layer "F.SilkS")
		)
		(fp_line
			(start 0.105328 0.201008)
			(end 0.105328 -0.198992)
			(stroke
				(width 0.1)
				(type solid)
			)
			(layer "F.SilkS")
		)
		(fp_line
			(start 0.105328 0.201008)
			(end -0.094672 0.001008)
			(stroke
				(width 0.1)
				(type solid)
			)
			(layer "F.SilkS")
		)
		(fp_line
			(start 0.105328 0.001008)
			(end 0.24 0.001)
			(stroke
				(width 0.1)
				(type solid)
			)
			(layer "F.SilkS")
		)
		(fp_line
			(start -0.094672 0.201008)
			(end -0.094672 -0.198992)
			(stroke
				(width 0.1)
				(type solid)
			)
			(layer "F.SilkS")
		)
		(fp_line
			(start -0.094672 0.001008)
			(end 0.105328 -0.198992)
			(stroke
				(width 0.1)
				(type solid)
			)
			(layer "F.SilkS")
		)
		(fp_line
			(start -0.094672 0.001008)
			(end -0.24 0.001008)
			(stroke
				(width 0.1)
				(type solid)
			)
			(layer "F.SilkS")
		)
		(fp_line
			(start -1.18 -0.319)
			(end -1.18 0.321)
			(stroke
				(width 0.15)
				(type solid)
			)
			(layer "F.SilkS")
		)
		(fp_rect
			(start 1.25 0.65)
			(end -1.25 -0.65)
			(stroke
				(width 0.05)
				(type solid)
			)
			(fill no)
			(layer "F.CrtYd")
		)
		(fp_line
			(start 0.599 0)
			(end 0.201 0)
			(stroke
				(width 0.15)
				(type solid)
			)
			(layer "F.Fab")
		)
		(fp_line
			(start 0.201 0.2)
			(end 0.201 0)
			(stroke
				(width 0.15)
				(type solid)
			)
			(layer "F.Fab")
		)
		(fp_line
			(start 0.201 0)
			(end 0.201 -0.202)
			(stroke
				(width 0.15)
				(type solid)
			)
			(layer "F.Fab")
		)
		(fp_line
			(start 0.201 -0.202)
			(end -0.101 0)
			(stroke
				(width 0.15)
				(type solid)
			)
			(layer "F.Fab")
		)
		(fp_line
			(start -0.101 0)
			(end 0.201 0.2)
			(stroke
				(width 0.15)
				(type solid)
			)
			(layer "F.Fab")
		)
		(fp_line
			(start -0.199 0.2)
			(end -0.199 0.1)
			(stroke
				(width 0.15)
				(type solid)
			)
			(layer "F.Fab")
		)
		(fp_line
			(start -0.199 0)
			(end -0.597 0)
			(stroke
				(width 0.15)
				(type solid)
			)
			(layer "F.Fab")
		)
		(fp_line
			(start -0.199 -0.202)
			(end -0.199 0.1)
			(stroke
				(width 0.15)
				(type solid)
			)
			(layer "F.Fab")
		)
		(fp_rect
			(start 0.848 0.4)
			(end -0.85 -0.402)
			(stroke
				(width 0.15)
				(type solid)
			)
			(fill no)
			(layer "F.Fab")
		)
		(pad "1" smd roundrect
			(at -0.7 0)
			(size 0.8 1)
			(layers "F.Cu" "F.Mask" "F.Paste")
			(roundrect_rratio 0.2)
			(net 699 "GNDD")
			(pinfunction "C")
			(pintype "passive")
		)
		(pad "2" smd roundrect
			(at 0.7 0)
			(size 0.8 1)
			(layers "F.Cu" "F.Mask" "F.Paste")
			(roundrect_rratio 0.2)
			(net 18 "Net-(D9-A)")
			(pinfunction "A")
			(pintype "passive")
		)
	)
	(footprint "antmicro-footprints:SW_KMR211NGLFS_SMD"
		(layer "F.Cu")
		(at 266.8 84 180)
		(property "Reference" "S3"
			(at 0.7 -2.6 180)
			(layer "F.SilkS")
			(effects
				(font
					(size 0.7 0.7)
					(thickness 0.15)
				)
				(justify left bottom)
			)
		)
		(property "Value" "SW_KMR211NGLFS_SMD"
			(at -3 3 180)
			(layer "F.Fab")
			(effects
				(font
					(size 0.7 0.7)
					(thickness 0.15)
				)
				(justify left bottom)
			)
		)
		(property "Description" "Tactile Switch, KMR 2 Series, Top Actuated, Surface Mount, Oval Button, 120 gf, 50mA at 32VDC"
			(at 0 0 180)
			(layer "F.Fab")
			(hide yes)
			(effects
				(font
					(size 1.27 1.27)
					(thickness 0.15)
				)
			)
		)
		(property "Author" "Antmicro"
			(at 533.6 168 0)
			(layer "F.Fab")
			(hide yes)
			(effects
				(font
					(size 1 1)
					(thickness 0.15)
				)
			)
		)
		(property "License" "Apache-2.0"
			(at 533.6 168 0)
			(layer "F.Fab")
			(hide yes)
			(effects
				(font
					(size 1 1)
					(thickness 0.15)
				)
			)
		)
		(property "MPN" "KMR211NGLFS"
			(at 533.6 168 0)
			(layer "F.Fab")
			(hide yes)
			(effects
				(font
					(size 1 1)
					(thickness 0.15)
				)
			)
		)
		(property "Manufacturer" "C&K"
			(at 533.6 168 0)
			(layer "F.Fab")
			(hide yes)
			(effects
				(font
					(size 1 1)
					(thickness 0.15)
				)
			)
		)
		(sheetname "User GPIO + LED + button + DIP switch")
		(sheetfile "user-gpio.kicad_sch")
		(attr smd)
		(fp_line
			(start 2.101 1.601)
			(end 2.101 1.48)
			(stroke
				(width 0.15)
				(type solid)
			)
			(layer "F.SilkS")
		)
		(fp_line
			(start 2.101 1.601)
			(end -2.1 1.601)
			(stroke
				(width 0.15)
				(type solid)
			)
			(layer "F.SilkS")
		)
		(fp_line
			(start 2.101 -1.58)
			(end 2.101 -1.459)
			(stroke
				(width 0.15)
				(type solid)
			)
			(layer "F.SilkS")
		)
		(fp_line
			(start 2.101 -1.6)
			(end -2.1 -1.6)
			(stroke
				(width 0.15)
				(type solid)
			)
			(layer "F.SilkS")
		)
		(fp_line
			(start -2.1 1.601)
			(end -2.1 1.48)
			(stroke
				(width 0.15)
				(type solid)
			)
			(layer "F.SilkS")
		)
		(fp_line
			(start -2.1 -1.6)
			(end -2.1 -1.499)
			(stroke
				(width 0.15)
				(type solid)
			)
			(layer "F.SilkS")
		)
		(fp_rect
			(start 2.751 1.75)
			(end -2.748 -1.749)
			(stroke
				(width 0.05)
				(type solid)
			)
			(fill no)
			(layer "F.CrtYd")
		)
		(fp_line
			(start 2.101 1.601)
			(end 2.101 -1.6)
			(stroke
				(width 0.15)
				(type solid)
			)
			(layer "F.Fab")
		)
		(fp_line
			(start 2.101 -1.6)
			(end -2.1 -1.6)
			(stroke
				(width 0.15)
				(type solid)
			)
			(layer "F.Fab")
		)
		(fp_line
			(start 0.25 0.802)
			(end -0.248 0.802)
			(stroke
				(width 0.15)
				(type solid)
			)
			(layer "F.Fab")
		)
		(fp_line
			(start -0.248 -0.8)
			(end 0.25 -0.8)
			(stroke
				(width 0.15)
				(type solid)
			)
			(layer "F.Fab")
		)
		(fp_line
			(start -2.1 1.601)
			(end 2.101 1.601)
			(stroke
				(width 0.15)
				(type solid)
			)
			(layer "F.Fab")
		)
		(fp_line
			(start -2.1 -1.6)
			(end -2.1 1.601)
			(stroke
				(width 0.15)
				(type solid)
			)
			(layer "F.Fab")
		)
		(fp_arc
			(start 0.25 -0.8)
			(mid 1.051001 0.001)
			(end 0.25 0.802)
			(stroke
				(width 0.15)
				(type solid)
			)
			(layer "F.Fab")
		)
		(fp_arc
			(start -0.248 0.802)
			(mid -1.050001 0.001)
			(end -0.248 -0.8)
			(stroke
				(width 0.15)
				(type solid)
			)
			(layer "F.Fab")
		)
		(pad "1" smd rect
			(at -2.048 -0.8)
			(size 0.9 1)
			(layers "F.Cu" "F.Mask" "F.Paste")
			(net 13 "/USER_IO.BUTTON1")
			(pinfunction "1")
			(pintype "passive")
		)
		(pad "2" smd rect
			(at 2.05 -0.8)
			(size 0.9 1)
			(layers "F.Cu" "F.Mask" "F.Paste")
			(net 13 "/USER_IO.BUTTON1")
			(pinfunction "2")
			(pintype "passive")
		)
		(pad "3" smd rect
			(at -2.048 0.802)
			(size 0.9 1)
			(layers "F.Cu" "F.Mask" "F.Paste")
			(net 1 "GND")
			(pinfunction "3")
			(pintype "passive")
		)
		(pad "4" smd rect
			(at 2.05 0.802)
			(size 0.9 1)
			(layers "F.Cu" "F.Mask" "F.Paste")
			(net 1 "GND")
			(pinfunction "4")
			(pintype "passive")
		)
	)
)
